(kicad_pcb
	(version 20260206)
	(generator "pcbnew")
	(generator_version "10.0")
	(general
		(thickness 1.6)
		(legacy_teardrops no)
	)
	(paper "A4")
	(title_block
		(title "Bryce Canyon_F.DPB_16315-1-OCP.brd")
		(comment 1 "Bryce Canyon / footprints 1456-1462 of 2223")
	)
	(layers
		(0 "F.Cu" signal "TOP")
		(4 "In1.Cu" signal "L2GND")
		(6 "In2.Cu" signal "L3")
		(8 "In3.Cu" signal "L4GND")
		(10 "In4.Cu" signal "L5")
		(12 "In5.Cu" signal "L6VCC")
		(14 "In6.Cu" signal "L7VCC")
		(16 "In7.Cu" signal "L8")
		(18 "In8.Cu" signal "L9GND")
		(20 "In9.Cu" signal "L10")
		(22 "In10.Cu" signal "L11GND")
		(2 "B.Cu" signal "BOTTOM")
		(9 "F.Adhes" user "F.Adhesive")
		(11 "B.Adhes" user "B.Adhesive")
		(13 "F.Paste" user "Package Geometry/Pastemask Top")
		(15 "B.Paste" user "Package Geometry/Pastemask Bottom")
		(5 "F.SilkS" user "Ref Des/Silkscreen Top")
		(7 "B.SilkS" user "Ref Des/Silkscreen Bottom")
		(1 "F.Mask" user "Board Geometry/Soldermask Top")
		(3 "B.Mask" user "Board Geometry/Soldermask Bottom")
		(17 "Dwgs.User" user "User.Drawings")
		(19 "Cmts.User" user "User.Comments")
		(21 "Eco1.User" user "User.Eco1")
		(23 "Eco2.User" user "User.Eco2")
		(25 "Edge.Cuts" user "Board Geometry/Outline")
		(27 "Margin" user)
		(31 "F.CrtYd" user "Package Geometry/Place Bound Top")
		(29 "B.CrtYd" user "Package Geometry/Place Bound Bottom")
		(35 "F.Fab" user "Ref Des/Assembly Top")
		(33 "B.Fab" user "Ref Des/Assembly Bottom")
	)
	(footprint ""
		(layer "F.Cu")
		(at 161.743898 -183.747918)
		(property "Reference" "TP82"
			(at 0 0 0)
			(layer "F.SilkS")
			(hide yes)
			(effects
				(font
					(size 1.27 1.27)
				)
			)
		)
		(property "Value" "TPAD32-GP"
			(at -0.0508 -1.6764 0)
			(unlocked yes)
			(layer "F.Fab")
			(hide yes)
			(effects
				(font
					(size 1.016 1.016)
					(thickness 0.1524)
				)
			)
		)
		(property "Device Type" "TPAD32"
			(at -0.0508 -3.2004 0)
			(unlocked yes)
			(layer "F.Fab")
			(hide yes)
			(effects
				(font
					(size 1.016 1.016)
					(thickness 0.1524)
				)
			)
		)
		(duplicate_pad_numbers_are_jumpers no)
		(fp_poly
			(pts
				(arc
					(start 0.4064 0)
					(mid -0.4064 0)
					(end 0.4064 0)
				)
			)
			(stroke
				(width 0)
				(type default)
			)
			(fill no)
			(layer "F.CrtYd")
		)
		(fp_poly
			(pts
				(arc
					(start 0.7112 0)
					(mid -0.7112 0)
					(end 0.7112 0)
				)
			)
			(stroke
				(width 0)
				(type default)
			)
			(fill no)
			(layer "F.Fab")
		)
		(pad "1" smd circle
			(at 0 0)
			(size 0.8128 0.8128)
			(layers "F.Cu" "F.Mask" "F.Paste")
			(net "ACT_HDD_16")
		)
	)
	(footprint ""
		(layer "F.Cu")
		(at 366.449102 -52.872894 -90)
		(property "Reference" "Q185"
			(at 0 0 270)
			(layer "F.SilkS")
			(hide yes)
			(effects
				(font
					(size 1.27 1.27)
				)
			)
		)
		(property "Value" "AO4406AL-GP"
			(at -3.707384 -1.5367 270)
			(unlocked yes)
			(layer "F.Fab")
			(hide yes)
			(effects
				(font
					(size 1.016 1.016)
					(thickness 0.1524)
				)
			)
		)
		(property "Device Type" "SOIC8H69"
			(at -3.707384 -3.0607 270)
			(unlocked yes)
			(layer "F.Fab")
			(hide yes)
			(effects
				(font
					(size 1.016 1.016)
					(thickness 0.1524)
				)
			)
		)
		(duplicate_pad_numbers_are_jumpers no)
		(fp_line
			(start -2.6289 3.4417)
			(end -2.6289 1.4732)
			(stroke
				(width 0.381)
				(type default)
			)
			(layer "F.SilkS")
		)
		(fp_line
			(start -2.7432 1.4224)
			(end -2.6416 1.4224)
			(stroke
				(width 0.1524)
				(type default)
			)
			(layer "F.SilkS")
		)
		(fp_line
			(start -2.7432 1.4224)
			(end 2.1336 1.4224)
			(stroke
				(width 0.1524)
				(type default)
			)
			(layer "F.SilkS")
		)
		(fp_line
			(start 2.1336 1.4224)
			(end 2.1336 -1.4224)
			(stroke
				(width 0.1524)
				(type default)
			)
			(layer "F.SilkS")
		)
		(fp_line
			(start -2.1844 -0.0508)
			(end -2.7178 0.508)
			(stroke
				(width 0.1524)
				(type default)
			)
			(layer "F.SilkS")
		)
		(fp_line
			(start -2.7178 -0.508)
			(end -2.1844 -0.0508)
			(stroke
				(width 0.1524)
				(type default)
			)
			(layer "F.SilkS")
		)
		(fp_line
			(start -2.7432 -1.4224)
			(end -2.7432 1.4224)
			(stroke
				(width 0.1524)
				(type default)
			)
			(layer "F.SilkS")
		)
		(fp_line
			(start 2.1336 -1.4224)
			(end -2.7432 -1.4224)
			(stroke
				(width 0.1524)
				(type default)
			)
			(layer "F.SilkS")
		)
		(fp_poly
			(pts
				(xy -2.2098 -1.4224) (xy -2.2098 1.4224) (xy 2.2098 1.4224) (xy 2.2098 -1.4224)
			)
			(stroke
				(width 0)
				(type default)
			)
			(fill yes)
			(layer "F.SilkS")
		)
		(fp_rect
			(start -2.450084 2.999994)
			(end 2.450084 -2.999994)
			(stroke
				(width 0)
				(type default)
			)
			(fill no)
			(layer "F.CrtYd")
		)
		(fp_poly
			(pts
				(xy -2.8194 3.6322) (xy -2.8194 -3.6322) (xy 2.8194 -3.6322) (xy 2.8194 1.18364) (xy 2.450084 1.18364)
				(xy 2.450084 -2.999994) (xy -2.450084 -2.999994) (xy -2.450084 2.999994) (xy 2.450084 2.999994)
				(xy 2.450084 1.18618) (xy 2.8194 1.18618) (xy 2.8194 3.6322)
			)
			(stroke
				(width 0)
				(type default)
			)
			(fill no)
			(layer "F.CrtYd")
		)
		(fp_rect
			(start -2.8194 3.6322)
			(end 2.8194 -3.6322)
			(stroke
				(width 0)
				(type default)
			)
			(fill no)
			(layer "F.Fab")
		)
		(pad "1" smd rect
			(at -1.905 2.54 270)
			(size 0.635 1.651)
			(layers "F.Cu" "F.Mask" "F.Paste")
			(net "P5V_HDD31")
		)
		(pad "2" smd rect
			(at -0.635 2.54 270)
			(size 0.635 1.651)
			(layers "F.Cu" "F.Mask" "F.Paste")
			(net "P5V_HDD31")
		)
		(pad "3" smd rect
			(at 0.635 2.54 270)
			(size 0.635 1.651)
			(layers "F.Cu" "F.Mask" "F.Paste")
			(net "P5V_HDD31")
		)
		(pad "4" smd rect
			(at 1.905 2.54 270)
			(size 0.635 1.651)
			(layers "F.Cu" "F.Mask" "F.Paste")
			(net "SW_HDD_P31")
		)
		(pad "5" smd rect
			(at 1.905 -2.54 270)
			(size 0.635 1.651)
			(layers "F.Cu" "F.Mask" "F.Paste")
			(net "P5V_A_4")
		)
		(pad "6" smd rect
			(at 0.635 -2.54 270)
			(size 0.635 1.651)
			(layers "F.Cu" "F.Mask" "F.Paste")
			(net "P5V_A_4")
		)
		(pad "7" smd rect
			(at -0.635 -2.54 270)
			(size 0.635 1.651)
			(layers "F.Cu" "F.Mask" "F.Paste")
			(net "P5V_A_4")
		)
		(pad "8" smd rect
			(at -1.905 -2.54 270)
			(size 0.635 1.651)
			(layers "F.Cu" "F.Mask" "F.Paste")
			(net "P5V_A_4")
		)
	)
	(footprint ""
		(layer "F.Cu")
		(at 46.415706 -279.156922 90)
		(property "Reference" "R169"
			(at 0 0 90)
			(layer "F.SilkS")
			(hide yes)
			(effects
				(font
					(size 1.27 1.27)
				)
			)
		)
		(property "Value" "200KR2F-L-GP"
			(at 0.064008 -3.993896 90)
			(unlocked yes)
			(layer "F.Fab")
			(hide yes)
			(effects
				(font
					(size 1.016 1.016)
					(thickness 0.1524)
				)
			)
		)
		(property "Device Type" "R402H16"
			(at 0.064008 -5.517896 90)
			(unlocked yes)
			(layer "F.Fab")
			(hide yes)
			(effects
				(font
					(size 1.016 1.016)
					(thickness 0.1524)
				)
			)
		)
		(duplicate_pad_numbers_are_jumpers no)
		(fp_line
			(start 0.508 -0.9398)
			(end -0.508 -0.9398)
			(stroke
				(width 0.1524)
				(type default)
			)
			(layer "F.SilkS")
		)
		(fp_line
			(start -0.508 -0.9398)
			(end -0.508 0.9398)
			(stroke
				(width 0.1524)
				(type default)
			)
			(layer "F.SilkS")
		)
		(fp_rect
			(start -0.508 0.9398)
			(end 0.508 -0.9398)
			(stroke
				(width 0)
				(type default)
			)
			(fill no)
			(layer "F.CrtYd")
		)
		(fp_rect
			(start -0.508 0.9398)
			(end 0.508 -0.9398)
			(stroke
				(width 0)
				(type default)
			)
			(fill no)
			(layer "F.Fab")
		)
		(pad "1" smd custom
			(at 0 -0.4445 90)
			(size 0.1397 0.1397)
			(layers "F.Cu" "F.Mask" "F.Paste")
			(net "SW_HDD_R1")
			(options
				(clearance outline)
				(anchor circle)
			)
			(primitives
				(gr_poly
					(pts
						(arc
							(start -0.1778 -0.2794)
							(mid -0.249642 -0.249642)
							(end -0.2794 -0.1778)
						)
						(arc
							(start -0.2794 0.1778)
							(mid -0.249642 0.249642)
							(end -0.1778 0.2794)
						)
						(arc
							(start 0.1778 0.2794)
							(mid 0.249642 0.249642)
							(end 0.2794 0.1778)
						)
						(arc
							(start 0.2794 -0.1778)
							(mid 0.249642 -0.249642)
							(end 0.1778 -0.2794)
						)
					)
					(width 0)
					(fill yes)
				)
			)
		)
		(pad "2" smd custom
			(at 0 0.4445 90)
			(size 0.1397 0.1397)
			(layers "F.Cu" "F.Mask" "F.Paste")
			(net "SW_HDD_N1")
			(options
				(clearance outline)
				(anchor circle)
			)
			(primitives
				(gr_poly
					(pts
						(arc
							(start -0.1778 -0.2794)
							(mid -0.249642 -0.249642)
							(end -0.2794 -0.1778)
						)
						(arc
							(start -0.2794 0.1778)
							(mid -0.249642 0.249642)
							(end -0.1778 0.2794)
						)
						(arc
							(start 0.1778 0.2794)
							(mid 0.249642 0.249642)
							(end 0.2794 0.1778)
						)
						(arc
							(start 0.2794 -0.1778)
							(mid 0.249642 -0.249642)
							(end 0.1778 -0.2794)
						)
					)
					(width 0)
					(fill yes)
				)
			)
		)
	)
	(footprint ""
		(layer "F.Cu")
		(at 237.493302 -261.133082 90)
		(property "Reference" "R40"
			(at 0 0 90)
			(layer "F.SilkS")
			(hide yes)
			(effects
				(font
					(size 1.27 1.27)
				)
			)
		)
		(property "Value" "0R2J-2-GP"
			(at 0.064008 -3.993896 90)
			(unlocked yes)
			(layer "F.Fab")
			(hide yes)
			(effects
				(font
					(size 1.016 1.016)
					(thickness 0.1524)
				)
			)
		)
		(property "Device Type" "R402H16"
			(at 0.064008 -5.517896 90)
			(unlocked yes)
			(layer "F.Fab")
			(hide yes)
			(effects
				(font
					(size 1.016 1.016)
					(thickness 0.1524)
				)
			)
		)
		(duplicate_pad_numbers_are_jumpers no)
		(fp_line
			(start 0.508 -0.9398)
			(end -0.508 -0.9398)
			(stroke
				(width 0.1524)
				(type default)
			)
			(layer "F.SilkS")
		)
		(fp_line
			(start -0.508 -0.9398)
			(end -0.508 0.9398)
			(stroke
				(width 0.1524)
				(type default)
			)
			(layer "F.SilkS")
		)
		(fp_rect
			(start -0.508 0.9398)
			(end 0.508 -0.9398)
			(stroke
				(width 0)
				(type default)
			)
			(fill no)
			(layer "F.CrtYd")
		)
		(fp_rect
			(start -0.508 0.9398)
			(end 0.508 -0.9398)
			(stroke
				(width 0)
				(type default)
			)
			(fill no)
			(layer "F.Fab")
		)
		(pad "1" smd custom
			(at 0 -0.4445 90)
			(size 0.1397 0.1397)
			(layers "F.Cu" "F.Mask" "F.Paste")
			(net "IO_EXP4_INT_N")
			(options
				(clearance outline)
				(anchor circle)
			)
			(primitives
				(gr_poly
					(pts
						(arc
							(start -0.1778 -0.2794)
							(mid -0.249642 -0.249642)
							(end -0.2794 -0.1778)
						)
						(arc
							(start -0.2794 0.1778)
							(mid -0.249642 0.249642)
							(end -0.1778 0.2794)
						)
						(arc
							(start 0.1778 0.2794)
							(mid 0.249642 0.249642)
							(end 0.2794 0.1778)
						)
						(arc
							(start 0.2794 -0.1778)
							(mid 0.249642 -0.249642)
							(end 0.1778 -0.2794)
						)
					)
					(width 0)
					(fill yes)
				)
			)
		)
		(pad "2" smd custom
			(at 0 0.4445 90)
			(size 0.1397 0.1397)
			(layers "F.Cu" "F.Mask" "F.Paste")
			(net "DRIVE_INSERT_ALERT_A_N")
			(options
				(clearance outline)
				(anchor circle)
			)
			(primitives
				(gr_poly
					(pts
						(arc
							(start -0.1778 -0.2794)
							(mid -0.249642 -0.249642)
							(end -0.2794 -0.1778)
						)
						(arc
							(start -0.2794 0.1778)
							(mid -0.249642 0.249642)
							(end -0.1778 0.2794)
						)
						(arc
							(start 0.1778 0.2794)
							(mid 0.249642 0.249642)
							(end 0.2794 0.1778)
						)
						(arc
							(start 0.2794 -0.1778)
							(mid 0.249642 -0.249642)
							(end 0.1778 -0.2794)
						)
					)
					(width 0)
					(fill yes)
				)
			)
		)
	)
	(footprint ""
		(layer "F.Cu")
		(at 118.890796 -189.462918 180)
		(property "Reference" "C242"
			(at 0 0 180)
			(layer "F.SilkS")
			(hide yes)
			(effects
				(font
					(size 1.27 1.27)
				)
			)
		)
		(property "Value" "SC1U25V3KX-GP"
			(at 0 -2.8194 180)
			(unlocked yes)
			(layer "F.Fab")
			(hide yes)
			(effects
				(font
					(size 1.016 1.016)
					(thickness 0.1524)
				)
			)
		)
		(property "Device Type" "C603H36"
			(at 0 -4.3434 180)
			(unlocked yes)
			(layer "F.Fab")
			(hide yes)
			(effects
				(font
					(size 1.016 1.016)
					(thickness 0.1524)
				)
			)
		)
		(duplicate_pad_numbers_are_jumpers no)
		(fp_line
			(start 0.508 0)
			(end -0.508 0)
			(stroke
				(width 0.2032)
				(type default)
			)
			(layer "F.SilkS")
		)
		(fp_rect
			(start -0.5842 1.3335)
			(end 0.5842 -1.3335)
			(stroke
				(width 0)
				(type default)
			)
			(fill no)
			(layer "F.CrtYd")
		)
		(fp_rect
			(start -0.5842 1.3335)
			(end 0.5842 -1.3335)
			(stroke
				(width 0)
				(type default)
			)
			(fill no)
			(layer "F.Fab")
		)
		(pad "1" smd custom
			(at 0 -0.762 180)
			(size 0.2159 0.2159)
			(layers "F.Cu" "F.Mask" "F.Paste")
			(net "P12V_HDD15")
			(options
				(clearance outline)
				(anchor circle)
			)
			(primitives
				(gr_poly
					(pts
						(arc
							(start -0.3302 -0.4318)
							(mid -0.402042 -0.402042)
							(end -0.4318 -0.3302)
						)
						(arc
							(start -0.4318 0.3302)
							(mid -0.402042 0.402042)
							(end -0.3302 0.4318)
						)
						(arc
							(start 0.3302 0.4318)
							(mid 0.402042 0.402042)
							(end 0.4318 0.3302)
						)
						(arc
							(start 0.4318 -0.3302)
							(mid 0.402042 -0.402042)
							(end 0.3302 -0.4318)
						)
					)
					(width 0)
					(fill yes)
				)
			)
		)
		(pad "2" smd custom
			(at 0 0.762 180)
			(size 0.2159 0.2159)
			(layers "F.Cu" "F.Mask" "F.Paste")
			(net "GND")
			(options
				(clearance outline)
				(anchor circle)
			)
			(primitives
				(gr_poly
					(pts
						(arc
							(start -0.3302 -0.4318)
							(mid -0.402042 -0.402042)
							(end -0.4318 -0.3302)
						)
						(arc
							(start -0.4318 0.3302)
							(mid -0.402042 0.402042)
							(end -0.3302 0.4318)
						)
						(arc
							(start 0.3302 0.4318)
							(mid 0.402042 0.402042)
							(end 0.4318 0.3302)
						)
						(arc
							(start 0.4318 -0.3302)
							(mid 0.402042 -0.402042)
							(end 0.3302 -0.4318)
						)
					)
					(width 0)
					(fill yes)
				)
			)
		)
	)
	(footprint ""
		(layer "F.Cu")
		(at 172.72 -170.158918 90)
		(property "Reference" "C270"
			(at 0 0 90)
			(layer "F.SilkS")
			(hide yes)
			(effects
				(font
					(size 1.27 1.27)
				)
			)
		)
		(property "Value" "SCD033U25V2KX-GP"
			(at 1.1811 -2.7051 90)
			(unlocked yes)
			(layer "F.Fab")
			(hide yes)
			(effects
				(font
					(size 1.016 1.016)
					(thickness 0.1524)
				)
			)
		)
		(property "Device Type" "C402H22"
			(at 1.1811 -4.2291 90)
			(unlocked yes)
			(layer "F.Fab")
			(hide yes)
			(effects
				(font
					(size 1.016 1.016)
					(thickness 0.1524)
				)
			)
		)
		(duplicate_pad_numbers_are_jumpers no)
		(fp_rect
			(start -0.4318 0.9525)
			(end 0.4318 -0.9525)
			(stroke
				(width 0)
				(type default)
			)
			(fill no)
			(layer "F.CrtYd")
		)
		(fp_rect
			(start -0.4318 0.9525)
			(end 0.4318 -0.9525)
			(stroke
				(width 0)
				(type default)
			)
			(fill no)
			(layer "F.Fab")
		)
		(pad "1" smd custom
			(at 0 -0.4445 90)
			(size 0.1524 0.1524)
			(layers "F.Cu" "F.Mask" "F.Paste")
			(net "P12V_A")
			(options
				(clearance outline)
				(anchor circle)
			)
			(primitives
				(gr_poly
					(pts
						(arc
							(start 0.3048 -0.2032)
							(mid 0.275042 -0.275042)
							(end 0.2032 -0.3048)
						)
						(arc
							(start -0.2032 -0.3048)
							(mid -0.275042 -0.275042)
							(end -0.3048 -0.2032)
						)
						(arc
							(start -0.3048 0.2032)
							(mid -0.275042 0.275042)
							(end -0.2032 0.3048)
						)
						(arc
							(start 0.2032 0.3048)
							(mid 0.275042 0.275042)
							(end 0.3048 0.2032)
						)
					)
					(width 0)
					(fill yes)
				)
			)
		)
		(pad "2" smd custom
			(at 0 0.4445 90)
			(size 0.1524 0.1524)
			(layers "F.Cu" "F.Mask" "F.Paste")
			(net "SW_HDD_N17")
			(options
				(clearance outline)
				(anchor circle)
			)
			(primitives
				(gr_poly
					(pts
						(arc
							(start 0.3048 -0.2032)
							(mid 0.275042 -0.275042)
							(end 0.2032 -0.3048)
						)
						(arc
							(start -0.2032 -0.3048)
							(mid -0.275042 -0.275042)
							(end -0.3048 -0.2032)
						)
						(arc
							(start -0.3048 0.2032)
							(mid -0.275042 0.275042)
							(end -0.2032 0.3048)
						)
						(arc
							(start 0.2032 0.3048)
							(mid 0.275042 0.275042)
							(end 0.3048 0.2032)
						)
					)
					(width 0)
					(fill yes)
				)
			)
		)
	)
	(footprint ""
		(layer "F.Cu")
		(at 191.135 -292.1)
		(property "Reference" "R245"
			(at 0 0 0)
			(layer "F.SilkS")
			(hide yes)
			(effects
				(font
					(size 1.27 1.27)
				)
			)
		)
		(property "Value" "10KR2F-2-GP"
			(at 0.064008 -3.993896 0)
			(unlocked yes)
			(layer "F.Fab")
			(hide yes)
			(effects
				(font
					(size 1.016 1.016)
					(thickness 0.1524)
				)
			)
		)
		(property "Device Type" "R402H16"
			(at 0.064008 -5.517896 0)
			(unlocked yes)
			(layer "F.Fab")
			(hide yes)
			(effects
				(font
					(size 1.016 1.016)
					(thickness 0.1524)
				)
			)
		)
		(duplicate_pad_numbers_are_jumpers no)
		(fp_line
			(start -0.508 -0.9398)
			(end -0.508 0.9398)
			(stroke
				(width 0.1524)
				(type default)
			)
			(layer "F.SilkS")
		)
		(fp_line
			(start 0.508 -0.9398)
			(end -0.508 -0.9398)
			(stroke
				(width 0.1524)
				(type default)
			)
			(layer "F.SilkS")
		)
		(fp_rect
			(start -0.508 0.9398)
			(end 0.508 -0.9398)
			(stroke
				(width 0)
				(type default)
			)
			(fill no)
			(layer "F.CrtYd")
		)
		(fp_rect
			(start -0.508 0.9398)
			(end 0.508 -0.9398)
			(stroke
				(width 0)
				(type default)
			)
			(fill no)
			(layer "F.Fab")
		)
		(pad "1" smd custom
			(at 0 -0.4445)
			(size 0.1397 0.1397)
			(layers "F.Cu" "F.Mask" "F.Paste")
			(net "P3V3_STBY_A")
			(options
				(clearance outline)
				(anchor circle)
			)
			(primitives
				(gr_poly
					(pts
						(arc
							(start -0.1778 -0.2794)
							(mid -0.249642 -0.249642)
							(end -0.2794 -0.1778)
						)
						(arc
							(start -0.2794 0.1778)
							(mid -0.249642 0.249642)
							(end -0.1778 0.2794)
						)
						(arc
							(start 0.1778 0.2794)
							(mid 0.249642 0.249642)
							(end 0.2794 0.1778)
						)
						(arc
							(start 0.2794 -0.1778)
							(mid 0.249642 -0.249642)
							(end 0.1778 -0.2794)
						)
					)
					(width 0)
					(fill yes)
				)
			)
		)
		(pad "2" smd custom
			(at 0 0.4445)
			(size 0.1397 0.1397)
			(layers "F.Cu" "F.Mask" "F.Paste")
			(net "HDD_PRSNT_5")
			(options
				(clearance outline)
				(anchor circle)
			)
			(primitives
				(gr_poly
					(pts
						(arc
							(start -0.1778 -0.2794)
							(mid -0.249642 -0.249642)
							(end -0.2794 -0.1778)
						)
						(arc
							(start -0.2794 0.1778)
							(mid -0.249642 0.249642)
							(end -0.1778 0.2794)
						)
						(arc
							(start 0.1778 0.2794)
							(mid 0.249642 0.249642)
							(end 0.2794 0.1778)
						)
						(arc
							(start 0.2794 -0.1778)
							(mid 0.249642 -0.249642)
							(end 0.1778 -0.2794)
						)
					)
					(width 0)
					(fill yes)
				)
			)
		)
	)
)
